# T6G (Grand Teton) — schematic netlist excerpt (pin names and nets, part order shuffled) for the footprints in the layout excerpt that follows; sources: Cadence DE-HDL packaged netlist, KiCad conversion of 04192023_DAF0TMB3IC0_F0TG_MB_C_brd_V02_OCP.brd

PPQ2  MOSFET_NCH_1D3S  PSMNR58-30YLH IC  pkg SOT1023  page 266
  \1\  = P12V_AUX
  \2\  = P12V_AUX
  \3\  = P12V_AUX
  \4\  = P12V_HSC_GATE_G6
  \5\  = P12V_MAIN_R

PC119  Q_CAP  22UF 16V 20% X6S  pkg C0805  page 192 : A = SW_P12V_AUX_PVDD_33_S5_FLT ; B = GND

(kicad_pcb
	(version 20260206)
	(generator "pcbnew")
	(generator_version "10.0")
	(general
		(thickness 1.6)
		(legacy_teardrops no)
	)
	(paper "A4")
	(title_block
		(title "04192023_DAF0TMB3IC0_F0TG_MB_C_brd_V02_OCP.brd")
		(comment 1 "Grand Teton / footprints 4022-4023 of 8354")
	)
	(layers
		(0 "F.Cu" signal "TOP")
		(4 "In1.Cu" signal "GND")
		(6 "In2.Cu" signal "IN1")
		(8 "In3.Cu" signal "GND1")
		(10 "In4.Cu" signal "IN2")
		(12 "In5.Cu" signal "GND2")
		(14 "In6.Cu" signal "IN3")
		(16 "In7.Cu" signal "GND3")
		(18 "In8.Cu" signal "VCC")
		(20 "In9.Cu" signal "VCC1")
		(22 "In10.Cu" signal "GND4")
		(24 "In11.Cu" signal "IN4")
		(26 "In12.Cu" signal "GND5")
		(28 "In13.Cu" signal "IN5")
		(30 "In14.Cu" signal "GND6")
		(32 "In15.Cu" signal "IN6")
		(34 "In16.Cu" signal "GND7")
		(2 "B.Cu" signal "BOTTOM")
		(9 "F.Adhes" user "F.Adhesive")
		(11 "B.Adhes" user "B.Adhesive")
		(13 "F.Paste" user "Package Geometry/Pastemask Top")
		(15 "B.Paste" user "Package Geometry/Pastemask Bottom")
		(5 "F.SilkS" user "Ref Des/Silkscreen Top")
		(7 "B.SilkS" user "Ref Des/Silkscreen Bottom")
		(1 "F.Mask" user "Board Geometry/Soldermask Top")
		(3 "B.Mask" user "Board Geometry/Soldermask Bottom")
		(17 "Dwgs.User" user "User.Drawings")
		(19 "Cmts.User" user "User.Comments")
		(21 "Eco1.User" user "User.Eco1")
		(23 "Eco2.User" user "User.Eco2")
		(25 "Edge.Cuts" user "Board Geometry/Outline")
		(27 "Margin" user)
		(31 "F.CrtYd" user "Package Geometry/Place Bound Top")
		(29 "B.CrtYd" user "Package Geometry/Place Bound Bottom")
		(35 "F.Fab" user "Ref Des/Assembly Top")
		(33 "B.Fab" user "Ref Des/Assembly Bottom")
	)
	(footprint ""
		(layer "F.Cu")
		(at 247.591072 -385.27736 90)
		(property "Reference" "PPQ2"
			(at -7.438644 -2.150872 0)
			(unlocked yes)
			(layer "F.SilkS")
			(effects
				(font
					(size 0.7874 0.5842)
					(thickness 0.1524)
				)
				(justify left)
			)
		)
		(property "Value" ""
			(at 0 0 90)
			(layer "F.Fab")
			(effects
				(font
					(size 1.27 1.27)
				)
			)
		)
		(duplicate_pad_numbers_are_jumpers no)
		(fp_line
			(start 2.350008 -2.649982)
			(end 2.350008 -2.4892)
			(stroke
				(width 0.1524)
				(type default)
			)
			(layer "F.SilkS")
		)
		(fp_line
			(start -2.350008 -2.649982)
			(end 2.350008 -2.649982)
			(stroke
				(width 0.1524)
				(type default)
			)
			(layer "F.SilkS")
		)
		(fp_line
			(start -2.350008 -2.4384)
			(end -2.350008 -2.649982)
			(stroke
				(width 0.1524)
				(type default)
			)
			(layer "F.SilkS")
		)
		(fp_line
			(start 2.350008 2.4892)
			(end 2.350008 2.649982)
			(stroke
				(width 0.1524)
				(type default)
			)
			(layer "F.SilkS")
		)
		(fp_line
			(start 2.350008 2.649982)
			(end -2.350008 2.649982)
			(stroke
				(width 0.1524)
				(type default)
			)
			(layer "F.SilkS")
		)
		(fp_line
			(start -2.350008 2.649982)
			(end -2.350008 2.413)
			(stroke
				(width 0.1524)
				(type default)
			)
			(layer "F.SilkS")
		)
		(fp_poly
			(pts
				(xy -3.45313 -3.467354) (xy -2.653538 -3.434588) (xy -3.115056 -2.411222)
			)
			(stroke
				(width 0)
				(type default)
			)
			(fill yes)
			(layer "F.SilkS")
		)
		(fp_line
			(start 2.350008 -2.649982)
			(end 2.350008 2.649982)
			(stroke
				(width 0.1)
				(type default)
			)
			(layer "F.Fab")
		)
		(fp_line
			(start -2.350008 -2.649982)
			(end 2.350008 -2.649982)
			(stroke
				(width 0.1)
				(type default)
			)
			(layer "F.Fab")
		)
		(fp_line
			(start 2.350008 2.649982)
			(end -2.350008 2.649982)
			(stroke
				(width 0.1)
				(type default)
			)
			(layer "F.Fab")
		)
		(fp_line
			(start -2.350008 2.649982)
			(end -2.350008 -2.649982)
			(stroke
				(width 0.1)
				(type default)
			)
			(layer "F.Fab")
		)
		(fp_poly
			(pts
				(xy -3.717544 -1.905) (xy -4.758944 -2.3241) (xy -4.758944 -1.524)
			)
			(stroke
				(width 0)
				(type default)
			)
			(fill yes)
			(layer "F.Fab")
		)
		(pad "1" smd rect
			(at -2.999994 -1.905)
			(size 0.7112 1.1684)
			(layers "F.Cu" "F.Mask" "F.Paste")
			(net "P12V_AUX")
		)
		(pad "2" smd rect
			(at -2.999994 -0.635)
			(size 0.7112 1.1684)
			(layers "F.Cu" "F.Mask" "F.Paste")
			(net "P12V_AUX")
		)
		(pad "3" smd rect
			(at -2.999994 0.635)
			(size 0.7112 1.1684)
			(layers "F.Cu" "F.Mask" "F.Paste")
			(net "P12V_AUX")
		)
		(pad "4" smd rect
			(at -2.999994 1.905)
			(size 0.7112 1.1684)
			(layers "F.Cu" "F.Mask" "F.Paste")
			(net "P12V_HSC_GATE_G6")
		)
		(pad "5" smd circle
			(at 0.925068 0)
			(size 0 0)
			(layers "F.Cu" "F.Mask" "F.Paste")
			(net "P12V_MAIN_R")
		)
		(zone
			(layer "F.Cu")
			(hatch none 0.5)
			(connect_pads
				(clearance 0)
			)
			(min_thickness 0.25)
			(keepout
				(tracks not_allowed)
				(vias allowed)
				(pads allowed)
				(copperpour not_allowed)
				(footprints allowed)
			)
			(placement
				(enabled no)
				(sheetname "")
			)
			(fill
				(thermal_gap 0.5)
				(thermal_bridge_width 0.5)
				(island_removal_mode 0)
			)
			(polygon
				(pts
					(xy 244.949472 -383.7178) (xy 250.232672 -383.7178) (xy 250.232672 -382.92786) (xy 244.949472 -382.92786)
				)
			)
		)
	)
	(footprint ""
		(layer "F.Cu")
		(at 199.941942 -346.023184 180)
		(property "Reference" "PC119"
			(at 0 0 180)
			(layer "F.SilkS")
			(hide yes)
			(effects
				(font
					(size 1.27 1.27)
				)
			)
		)
		(property "Value" ""
			(at 0 0 180)
			(layer "F.Fab")
			(effects
				(font
					(size 1.27 1.27)
				)
			)
		)
		(duplicate_pad_numbers_are_jumpers no)
		(fp_line
			(start 1.524 0.762)
			(end -1.524 0.762)
			(stroke
				(width 0.1524)
				(type default)
			)
			(layer "F.SilkS")
		)
		(fp_line
			(start 1.524 -0.762)
			(end 1.524 0.762)
			(stroke
				(width 0.1524)
				(type default)
			)
			(layer "F.SilkS")
		)
		(fp_line
			(start -1.524 0.762)
			(end -1.524 -0.762)
			(stroke
				(width 0.1524)
				(type default)
			)
			(layer "F.SilkS")
		)
		(fp_line
			(start -1.524 -0.762)
			(end 1.524 -0.762)
			(stroke
				(width 0.1524)
				(type default)
			)
			(layer "F.SilkS")
		)
		(fp_line
			(start 1.1049 0.724916)
			(end 1.1049 -0.724916)
			(stroke
				(width 0.1)
				(type default)
			)
			(layer "F.Fab")
		)
		(fp_line
			(start 1.1049 -0.724916)
			(end -1.1049 -0.724916)
			(stroke
				(width 0.1)
				(type default)
			)
			(layer "F.Fab")
		)
		(fp_line
			(start -1.1049 0.724916)
			(end 1.1049 0.724916)
			(stroke
				(width 0.1)
				(type default)
			)
			(layer "F.Fab")
		)
		(fp_line
			(start -1.1049 -0.724916)
			(end -1.1049 0.724916)
			(stroke
				(width 0.1)
				(type default)
			)
			(layer "F.Fab")
		)
		(pad "1" smd rect
			(at -0.889 0)
			(size 1.016 1.27)
			(layers "F.Cu" "F.Mask" "F.Paste")
			(net "SW_P12V_AUX_PVDD_33_S5_FLT")
		)
		(pad "2" smd rect
			(at 0.889 0)
			(size 1.016 1.27)
			(layers "F.Cu" "F.Mask" "F.Paste")
			(net "GND")
		)
	)
)
